(kicad_pcb
	(version 20260206)
	(generator "pcbnew")
	(generator_version "10.0")
	(general
		(thickness 1.6)
		(legacy_teardrops no)
	)
	(paper "A4")
	(title_block
		(title "peb — Lightning_PEB_BRD.brd")
		(comment 1 "Lightning (Wiwynn / Facebook NVMe JBOF) / footprints 1667-1674 of 2563")
	)
	(layers
		(0 "F.Cu" signal "TOP")
		(4 "In1.Cu" signal "L2GND")
		(6 "In2.Cu" signal "L3")
		(8 "In3.Cu" signal "L4VCC")
		(10 "In4.Cu" signal "L5VCC")
		(12 "In5.Cu" signal "L6")
		(14 "In6.Cu" signal "L7GND")
		(2 "B.Cu" signal "BOTTOM")
		(9 "F.Adhes" user "F.Adhesive")
		(11 "B.Adhes" user "B.Adhesive")
		(13 "F.Paste" user "Package Geometry/Pastemask Top")
		(15 "B.Paste" user "Package Geometry/Pastemask Bottom")
		(5 "F.SilkS" user "Ref Des/Silkscreen Top")
		(7 "B.SilkS" user "Ref Des/Silkscreen Bottom")
		(1 "F.Mask" user "Board Geometry/Soldermask Top")
		(3 "B.Mask" user "Board Geometry/Soldermask Bottom")
		(17 "Dwgs.User" user "User.Drawings")
		(19 "Cmts.User" user "User.Comments")
		(21 "Eco1.User" user "User.Eco1")
		(23 "Eco2.User" user "User.Eco2")
		(25 "Edge.Cuts" user "Board Geometry/Outline")
		(27 "Margin" user)
		(31 "F.CrtYd" user "Package Geometry/Place Bound Top")
		(29 "B.CrtYd" user "Package Geometry/Place Bound Bottom")
		(35 "F.Fab" user "Ref Des/Assembly Top")
		(33 "B.Fab" user "Ref Des/Assembly Bottom")
	)
	(footprint ""
		(layer "B.Cu")
		(at 76.454 -189.484)
		(property "Reference" "R146"
			(at 0 0 0)
			(layer "B.SilkS")
			(hide yes)
			(effects
				(font
					(size 1.27 1.27)
				)
				(justify mirror)
			)
		)
		(property "Value" "4K7R2F-GP"
			(at -0.064008 -3.993896 0)
			(unlocked yes)
			(layer "B.Fab")
			(hide yes)
			(effects
				(font
					(size 1.016 1.016)
					(thickness 0.1524)
				)
				(justify mirror)
			)
		)
		(property "Device Type" "R402H16"
			(at -0.064008 -5.517896 0)
			(unlocked yes)
			(layer "B.Fab")
			(hide yes)
			(effects
				(font
					(size 1.016 1.016)
					(thickness 0.1524)
				)
				(justify mirror)
			)
		)
		(duplicate_pad_numbers_are_jumpers no)
		(fp_line
			(start -0.508 -0.9398)
			(end 0.508 -0.9398)
			(stroke
				(width 0.1524)
				(type default)
			)
			(layer "B.SilkS")
		)
		(fp_line
			(start 0.508 -0.9398)
			(end 0.508 0.9398)
			(stroke
				(width 0.1524)
				(type default)
			)
			(layer "B.SilkS")
		)
		(fp_rect
			(start 0.508 0.9398)
			(end -0.508 -0.9398)
			(stroke
				(width 0)
				(type default)
			)
			(fill no)
			(layer "B.CrtYd")
		)
		(fp_rect
			(start 0.508 0.9398)
			(end -0.508 -0.9398)
			(stroke
				(width 0)
				(type default)
			)
			(fill no)
			(layer "B.Fab")
		)
		(pad "1" smd custom
			(at 0 -0.4445 180)
			(size 0.1397 0.1397)
			(layers "B.Cu" "B.Mask" "B.Paste")
			(net "BMC_SSD_RST#0_A5")
			(options
				(clearance outline)
				(anchor circle)
			)
			(primitives
				(gr_poly
					(pts
						(arc
							(start -0.1778 0.2794)
							(mid -0.249642 0.249642)
							(end -0.2794 0.1778)
						)
						(arc
							(start -0.2794 -0.1778)
							(mid -0.249642 -0.249642)
							(end -0.1778 -0.2794)
						)
						(arc
							(start 0.1778 -0.2794)
							(mid 0.249642 -0.249642)
							(end 0.2794 -0.1778)
						)
						(arc
							(start 0.2794 0.1778)
							(mid 0.249642 0.249642)
							(end 0.1778 0.2794)
						)
					)
					(width 0)
					(fill yes)
				)
			)
		)
		(pad "2" smd custom
			(at 0 0.4445 180)
			(size 0.1397 0.1397)
			(layers "B.Cu" "B.Mask" "B.Paste")
			(net "P3V3_STBY")
			(options
				(clearance outline)
				(anchor circle)
			)
			(primitives
				(gr_poly
					(pts
						(arc
							(start -0.1778 0.2794)
							(mid -0.249642 0.249642)
							(end -0.2794 0.1778)
						)
						(arc
							(start -0.2794 -0.1778)
							(mid -0.249642 -0.249642)
							(end -0.1778 -0.2794)
						)
						(arc
							(start 0.1778 -0.2794)
							(mid 0.249642 -0.249642)
							(end 0.2794 -0.1778)
						)
						(arc
							(start 0.2794 0.1778)
							(mid 0.249642 0.249642)
							(end 0.1778 0.2794)
						)
					)
					(width 0)
					(fill yes)
				)
			)
		)
	)
	(footprint ""
		(layer "B.Cu")
		(at 23.90648 -138.602974 90)
		(property "Reference" "R362"
			(at 0 0 90)
			(layer "B.SilkS")
			(hide yes)
			(effects
				(font
					(size 1.27 1.27)
				)
				(justify mirror)
			)
		)
		(property "Value" "3K3R2F-2-GP"
			(at -0.064008 -3.993896 90)
			(unlocked yes)
			(layer "B.Fab")
			(hide yes)
			(effects
				(font
					(size 1.016 1.016)
					(thickness 0.1524)
				)
				(justify mirror)
			)
		)
		(property "Device Type" "R402H16"
			(at -0.064008 -5.517896 90)
			(unlocked yes)
			(layer "B.Fab")
			(hide yes)
			(effects
				(font
					(size 1.016 1.016)
					(thickness 0.1524)
				)
				(justify mirror)
			)
		)
		(duplicate_pad_numbers_are_jumpers no)
		(fp_line
			(start 0.508 -0.9398)
			(end 0.508 0.9398)
			(stroke
				(width 0.1524)
				(type default)
			)
			(layer "B.SilkS")
		)
		(fp_line
			(start -0.508 -0.9398)
			(end 0.508 -0.9398)
			(stroke
				(width 0.1524)
				(type default)
			)
			(layer "B.SilkS")
		)
		(fp_rect
			(start 0.508 0.9398)
			(end -0.508 -0.9398)
			(stroke
				(width 0)
				(type default)
			)
			(fill no)
			(layer "B.CrtYd")
		)
		(fp_rect
			(start 0.508 0.9398)
			(end -0.508 -0.9398)
			(stroke
				(width 0)
				(type default)
			)
			(fill no)
			(layer "B.Fab")
		)
		(pad "1" smd custom
			(at 0 -0.4445 270)
			(size 0.1397 0.1397)
			(layers "B.Cu" "B.Mask" "B.Paste")
			(net "P3V3_STBY")
			(options
				(clearance outline)
				(anchor circle)
			)
			(primitives
				(gr_poly
					(pts
						(arc
							(start -0.1778 0.2794)
							(mid -0.249642 0.249642)
							(end -0.2794 0.1778)
						)
						(arc
							(start -0.2794 -0.1778)
							(mid -0.249642 -0.249642)
							(end -0.1778 -0.2794)
						)
						(arc
							(start 0.1778 -0.2794)
							(mid 0.249642 -0.249642)
							(end 0.2794 -0.1778)
						)
						(arc
							(start 0.2794 0.1778)
							(mid 0.249642 0.249642)
							(end 0.1778 0.2794)
						)
					)
					(width 0)
					(fill yes)
				)
			)
		)
		(pad "2" smd custom
			(at 0 0.4445 270)
			(size 0.1397 0.1397)
			(layers "B.Cu" "B.Mask" "B.Paste")
			(net "ROMD5")
			(options
				(clearance outline)
				(anchor circle)
			)
			(primitives
				(gr_poly
					(pts
						(arc
							(start -0.1778 0.2794)
							(mid -0.249642 0.249642)
							(end -0.2794 0.1778)
						)
						(arc
							(start -0.2794 -0.1778)
							(mid -0.249642 -0.249642)
							(end -0.1778 -0.2794)
						)
						(arc
							(start 0.1778 -0.2794)
							(mid 0.249642 -0.249642)
							(end 0.2794 -0.1778)
						)
						(arc
							(start 0.2794 0.1778)
							(mid 0.249642 0.249642)
							(end 0.1778 0.2794)
						)
					)
					(width 0)
					(fill yes)
				)
			)
		)
	)
	(footprint ""
		(layer "B.Cu")
		(at 235.1024 -43.997372 90)
		(property "Reference" "C433"
			(at 0 0 90)
			(layer "B.SilkS")
			(hide yes)
			(effects
				(font
					(size 1.27 1.27)
				)
				(justify mirror)
			)
		)
		(property "Value" "SCD1U16V1KX-1-GP"
			(at 2.8321 -1.7399 90)
			(unlocked yes)
			(layer "B.Fab")
			(hide yes)
			(effects
				(font
					(size 1.016 1.016)
					(thickness 0.1524)
				)
				(justify mirror)
			)
		)
		(property "Device Type" "C0201H13"
			(at 2.8321 -3.2639 90)
			(unlocked yes)
			(layer "B.Fab")
			(hide yes)
			(effects
				(font
					(size 1.016 1.016)
					(thickness 0.1524)
				)
				(justify mirror)
			)
		)
		(duplicate_pad_numbers_are_jumpers no)
		(fp_rect
			(start 0.2794 0.6477)
			(end -0.2794 -0.6477)
			(stroke
				(width 0)
				(type default)
			)
			(fill no)
			(layer "B.CrtYd")
		)
		(fp_rect
			(start 0.2794 0.6477)
			(end -0.2794 -0.6477)
			(stroke
				(width 0)
				(type default)
			)
			(fill no)
			(layer "B.Fab")
		)
		(pad "1" smd custom
			(at 0 -0.2794 270)
			(size 0.0762 0.0762)
			(layers "B.Cu" "B.Mask" "B.Paste")
			(net "DUT_VDD")
			(options
				(clearance outline)
				(anchor circle)
			)
			(primitives
				(gr_poly
					(pts
						(arc
							(start 0.1524 0.127)
							(mid 0.137521 0.162921)
							(end 0.1016 0.1778)
						)
						(arc
							(start -0.1016 0.1778)
							(mid -0.137521 0.162921)
							(end -0.1524 0.127)
						)
						(arc
							(start -0.1524 -0.127)
							(mid -0.137521 -0.162921)
							(end -0.1016 -0.1778)
						)
						(arc
							(start 0.1016 -0.1778)
							(mid 0.137521 -0.162921)
							(end 0.1524 -0.127)
						)
					)
					(width 0)
					(fill yes)
				)
			)
		)
		(pad "2" smd custom
			(at 0 0.2794 270)
			(size 0.0762 0.0762)
			(layers "B.Cu" "B.Mask" "B.Paste")
			(net "GND")
			(options
				(clearance outline)
				(anchor circle)
			)
			(primitives
				(gr_poly
					(pts
						(arc
							(start 0.1524 0.127)
							(mid 0.137521 0.162921)
							(end 0.1016 0.1778)
						)
						(arc
							(start -0.1016 0.1778)
							(mid -0.137521 0.162921)
							(end -0.1524 0.127)
						)
						(arc
							(start -0.1524 -0.127)
							(mid -0.137521 -0.162921)
							(end -0.1016 -0.1778)
						)
						(arc
							(start 0.1016 -0.1778)
							(mid 0.137521 -0.162921)
							(end 0.1524 -0.127)
						)
					)
					(width 0)
					(fill yes)
				)
			)
		)
	)
	(footprint ""
		(layer "B.Cu")
		(at 269.580868 -18.820384 180)
		(property "Reference" "R728"
			(at 0 0 0)
			(layer "B.SilkS")
			(hide yes)
			(effects
				(font
					(size 1.27 1.27)
				)
				(justify mirror)
			)
		)
		(property "Value" "0R2J-2-GP"
			(at -0.064008 -3.993896 180)
			(unlocked yes)
			(layer "B.Fab")
			(hide yes)
			(effects
				(font
					(size 1.016 1.016)
					(thickness 0.1524)
				)
				(justify mirror)
			)
		)
		(property "Device Type" "R402H16"
			(at -0.064008 -5.517896 180)
			(unlocked yes)
			(layer "B.Fab")
			(hide yes)
			(effects
				(font
					(size 1.016 1.016)
					(thickness 0.1524)
				)
				(justify mirror)
			)
		)
		(duplicate_pad_numbers_are_jumpers no)
		(fp_line
			(start 0.508 -0.9398)
			(end 0.508 0.9398)
			(stroke
				(width 0.1524)
				(type default)
			)
			(layer "B.SilkS")
		)
		(fp_line
			(start -0.508 -0.9398)
			(end 0.508 -0.9398)
			(stroke
				(width 0.1524)
				(type default)
			)
			(layer "B.SilkS")
		)
		(fp_rect
			(start 0.508 0.9398)
			(end -0.508 -0.9398)
			(stroke
				(width 0)
				(type default)
			)
			(fill no)
			(layer "B.CrtYd")
		)
		(fp_rect
			(start 0.508 0.9398)
			(end -0.508 -0.9398)
			(stroke
				(width 0)
				(type default)
			)
			(fill no)
			(layer "B.Fab")
		)
		(pad "1" smd custom
			(at 0 -0.4445)
			(size 0.1397 0.1397)
			(layers "B.Cu" "B.Mask" "B.Paste")
			(net "8644_USB_DN5")
			(options
				(clearance outline)
				(anchor circle)
			)
			(primitives
				(gr_poly
					(pts
						(arc
							(start -0.1778 0.2794)
							(mid -0.249642 0.249642)
							(end -0.2794 0.1778)
						)
						(arc
							(start -0.2794 -0.1778)
							(mid -0.249642 -0.249642)
							(end -0.1778 -0.2794)
						)
						(arc
							(start 0.1778 -0.2794)
							(mid 0.249642 -0.249642)
							(end 0.2794 -0.1778)
						)
						(arc
							(start 0.2794 0.1778)
							(mid 0.249642 0.249642)
							(end 0.1778 0.2794)
						)
					)
					(width 0)
					(fill yes)
				)
			)
		)
		(pad "2" smd custom
			(at 0 0.4445)
			(size 0.1397 0.1397)
			(layers "B.Cu" "B.Mask" "B.Paste")
			(net "P3V3_STBY")
			(options
				(clearance outline)
				(anchor circle)
			)
			(primitives
				(gr_poly
					(pts
						(arc
							(start -0.1778 0.2794)
							(mid -0.249642 0.249642)
							(end -0.2794 0.1778)
						)
						(arc
							(start -0.2794 -0.1778)
							(mid -0.249642 -0.249642)
							(end -0.1778 -0.2794)
						)
						(arc
							(start 0.1778 -0.2794)
							(mid 0.249642 -0.249642)
							(end 0.2794 -0.1778)
						)
						(arc
							(start 0.2794 0.1778)
							(mid 0.249642 0.249642)
							(end 0.1778 0.2794)
						)
					)
					(width 0)
					(fill yes)
				)
			)
		)
	)
	(footprint ""
		(layer "B.Cu")
		(at 51.5366 -129.7686 90)
		(property "Reference" "R533"
			(at 0 0 90)
			(layer "B.SilkS")
			(hide yes)
			(effects
				(font
					(size 1.27 1.27)
				)
				(justify mirror)
			)
		)
		(property "Value" "0R2J-2-GP"
			(at -0.064008 -3.993896 90)
			(unlocked yes)
			(layer "B.Fab")
			(hide yes)
			(effects
				(font
					(size 1.016 1.016)
					(thickness 0.1524)
				)
				(justify mirror)
			)
		)
		(property "Device Type" "R402H16"
			(at -0.064008 -5.517896 90)
			(unlocked yes)
			(layer "B.Fab")
			(hide yes)
			(effects
				(font
					(size 1.016 1.016)
					(thickness 0.1524)
				)
				(justify mirror)
			)
		)
		(duplicate_pad_numbers_are_jumpers no)
		(fp_line
			(start 0.508 -0.9398)
			(end 0.508 0.9398)
			(stroke
				(width 0.1524)
				(type default)
			)
			(layer "B.SilkS")
		)
		(fp_line
			(start -0.508 -0.9398)
			(end 0.508 -0.9398)
			(stroke
				(width 0.1524)
				(type default)
			)
			(layer "B.SilkS")
		)
		(fp_rect
			(start 0.508 0.9398)
			(end -0.508 -0.9398)
			(stroke
				(width 0)
				(type default)
			)
			(fill no)
			(layer "B.CrtYd")
		)
		(fp_rect
			(start 0.508 0.9398)
			(end -0.508 -0.9398)
			(stroke
				(width 0)
				(type default)
			)
			(fill no)
			(layer "B.Fab")
		)
		(pad "1" smd custom
			(at 0 -0.4445 270)
			(size 0.1397 0.1397)
			(layers "B.Cu" "B.Mask" "B.Paste")
			(net "BMC_USB1_HDP2")
			(options
				(clearance outline)
				(anchor circle)
			)
			(primitives
				(gr_poly
					(pts
						(arc
							(start -0.1778 0.2794)
							(mid -0.249642 0.249642)
							(end -0.2794 0.1778)
						)
						(arc
							(start -0.2794 -0.1778)
							(mid -0.249642 -0.249642)
							(end -0.1778 -0.2794)
						)
						(arc
							(start 0.1778 -0.2794)
							(mid 0.249642 -0.249642)
							(end 0.2794 -0.1778)
						)
						(arc
							(start 0.2794 0.1778)
							(mid 0.249642 0.249642)
							(end 0.1778 0.2794)
						)
					)
					(width 0)
					(fill yes)
				)
			)
		)
		(pad "2" smd custom
			(at 0 0.4445 270)
			(size 0.1397 0.1397)
			(layers "B.Cu" "B.Mask" "B.Paste")
			(net "USB_P4_DP_BMC")
			(options
				(clearance outline)
				(anchor circle)
			)
			(primitives
				(gr_poly
					(pts
						(arc
							(start -0.1778 0.2794)
							(mid -0.249642 0.249642)
							(end -0.2794 0.1778)
						)
						(arc
							(start -0.2794 -0.1778)
							(mid -0.249642 -0.249642)
							(end -0.1778 -0.2794)
						)
						(arc
							(start 0.1778 -0.2794)
							(mid 0.249642 -0.249642)
							(end 0.2794 -0.1778)
						)
						(arc
							(start 0.2794 0.1778)
							(mid 0.249642 0.249642)
							(end 0.1778 0.2794)
						)
					)
					(width 0)
					(fill yes)
				)
			)
		)
	)
	(footprint ""
		(layer "B.Cu")
		(at 35.814 -116.84 180)
		(property "Reference" "R285"
			(at 0 0 0)
			(layer "B.SilkS")
			(hide yes)
			(effects
				(font
					(size 1.27 1.27)
				)
				(justify mirror)
			)
		)
		(property "Value" "22R2J-2-GP"
			(at -0.064008 -3.993896 180)
			(unlocked yes)
			(layer "B.Fab")
			(hide yes)
			(effects
				(font
					(size 1.016 1.016)
					(thickness 0.1524)
				)
				(justify mirror)
			)
		)
		(property "Device Type" "R402H16"
			(at -0.064008 -5.517896 180)
			(unlocked yes)
			(layer "B.Fab")
			(hide yes)
			(effects
				(font
					(size 1.016 1.016)
					(thickness 0.1524)
				)
				(justify mirror)
			)
		)
		(duplicate_pad_numbers_are_jumpers no)
		(fp_line
			(start 0.508 -0.9398)
			(end 0.508 0.9398)
			(stroke
				(width 0.1524)
				(type default)
			)
			(layer "B.SilkS")
		)
		(fp_line
			(start -0.508 -0.9398)
			(end 0.508 -0.9398)
			(stroke
				(width 0.1524)
				(type default)
			)
			(layer "B.SilkS")
		)
		(fp_rect
			(start 0.508 0.9398)
			(end -0.508 -0.9398)
			(stroke
				(width 0)
				(type default)
			)
			(fill no)
			(layer "B.CrtYd")
		)
		(fp_rect
			(start 0.508 0.9398)
			(end -0.508 -0.9398)
			(stroke
				(width 0)
				(type default)
			)
			(fill no)
			(layer "B.Fab")
		)
		(pad "1" smd custom
			(at 0 -0.4445)
			(size 0.1397 0.1397)
			(layers "B.Cu" "B.Mask" "B.Paste")
			(net "RMII_BMC_PHY_TXD1")
			(options
				(clearance outline)
				(anchor circle)
			)
			(primitives
				(gr_poly
					(pts
						(arc
							(start -0.1778 0.2794)
							(mid -0.249642 0.249642)
							(end -0.2794 0.1778)
						)
						(arc
							(start -0.2794 -0.1778)
							(mid -0.249642 -0.249642)
							(end -0.1778 -0.2794)
						)
						(arc
							(start 0.1778 -0.2794)
							(mid 0.249642 -0.249642)
							(end 0.2794 -0.1778)
						)
						(arc
							(start 0.2794 0.1778)
							(mid 0.249642 0.249642)
							(end 0.1778 0.2794)
						)
					)
					(width 0)
					(fill yes)
				)
			)
		)
		(pad "2" smd custom
			(at 0 0.4445)
			(size 0.1397 0.1397)
			(layers "B.Cu" "B.Mask" "B.Paste")
			(net "RMII0_BMC_C_PHY_TXD1")
			(options
				(clearance outline)
				(anchor circle)
			)
			(primitives
				(gr_poly
					(pts
						(arc
							(start -0.1778 0.2794)
							(mid -0.249642 0.249642)
							(end -0.2794 0.1778)
						)
						(arc
							(start -0.2794 -0.1778)
							(mid -0.249642 -0.249642)
							(end -0.1778 -0.2794)
						)
						(arc
							(start 0.1778 -0.2794)
							(mid 0.249642 -0.249642)
							(end 0.2794 -0.1778)
						)
						(arc
							(start 0.2794 0.1778)
							(mid 0.249642 0.249642)
							(end 0.1778 0.2794)
						)
					)
					(width 0)
					(fill yes)
				)
			)
		)
	)
	(footprint ""
		(layer "B.Cu")
		(at 319.659 -55.372)
		(property "Reference" "PC176"
			(at 0 0 0)
			(layer "B.SilkS")
			(hide yes)
			(effects
				(font
					(size 1.27 1.27)
				)
				(justify mirror)
			)
		)
		(property "Value" "SC22U6D3V5MX-5-GP"
			(at 0.0762 -6.1214 0)
			(unlocked yes)
			(layer "B.Fab")
			(hide yes)
			(effects
				(font
					(size 1.016 1.016)
					(thickness 0.1524)
				)
				(justify mirror)
			)
		)
		(property "Device Type" "C805H56"
			(at 0.0762 -8.1534 0)
			(unlocked yes)
			(layer "B.Fab")
			(hide yes)
			(effects
				(font
					(size 1.016 1.016)
					(thickness 0.1524)
				)
				(justify mirror)
			)
		)
		(duplicate_pad_numbers_are_jumpers no)
		(fp_line
			(start -0.635 0)
			(end 0.635 0)
			(stroke
				(width 0.508)
				(type default)
			)
			(layer "B.SilkS")
		)
		(fp_rect
			(start 0.9652 1.778)
			(end -0.9652 -1.778)
			(stroke
				(width 0)
				(type default)
			)
			(fill no)
			(layer "B.CrtYd")
		)
		(fp_poly
			(pts
				(xy 0.9652 -1.778) (xy -0.9652 -1.778) (xy -0.9652 1.778) (xy 0.9652 1.778)
			)
			(stroke
				(width 0)
				(type default)
			)
			(fill no)
			(layer "B.Fab")
		)
		(pad "1" smd rect
			(at 0 -0.9652 180)
			(size 1.397 1.143)
			(layers "B.Cu" "B.Mask" "B.Paste")
			(net "P0V9_E")
		)
		(pad "2" smd rect
			(at 0 0.9652 180)
			(size 1.397 1.143)
			(layers "B.Cu" "B.Mask" "B.Paste")
			(net "GND")
		)
	)
	(footprint ""
		(layer "B.Cu")
		(at 246.126 -69.977 90)
		(property "Reference" "C495"
			(at 0 0 90)
			(layer "B.SilkS")
			(hide yes)
			(effects
				(font
					(size 1.27 1.27)
				)
				(justify mirror)
			)
		)
		(property "Value" "SC100U4V5MX-1-GP"
			(at 0.0762 -6.1214 90)
			(unlocked yes)
			(layer "B.Fab")
			(hide yes)
			(effects
				(font
					(size 1.016 1.016)
					(thickness 0.1524)
				)
				(justify mirror)
			)
		)
		(property "Device Type" "C805H58"
			(at 0.0762 -8.1534 90)
			(unlocked yes)
			(layer "B.Fab")
			(hide yes)
			(effects
				(font
					(size 1.016 1.016)
					(thickness 0.1524)
				)
				(justify mirror)
			)
		)
		(duplicate_pad_numbers_are_jumpers no)
		(fp_line
			(start -0.635 0)
			(end 0.635 0)
			(stroke
				(width 0.508)
				(type default)
			)
			(layer "B.SilkS")
		)
		(fp_rect
			(start 0.9652 1.778)
			(end -0.9652 -1.778)
			(stroke
				(width 0)
				(type default)
			)
			(fill no)
			(layer "B.CrtYd")
		)
		(fp_poly
			(pts
				(xy 0.9652 -1.778) (xy -0.9652 -1.778) (xy -0.9652 1.778) (xy 0.9652 1.778)
			)
			(stroke
				(width 0)
				(type default)
			)
			(fill no)
			(layer "B.Fab")
		)
		(pad "1" smd rect
			(at 0 -0.9652 270)
			(size 1.397 1.143)
			(layers "B.Cu" "B.Mask" "B.Paste")
			(net "DUT_AVD_TX")
		)
		(pad "2" smd rect
			(at 0 0.9652 270)
			(size 1.397 1.143)
			(layers "B.Cu" "B.Mask" "B.Paste")
			(net "GND")
		)
	)
)
